# SCM (Grand Teton) — schematic netlist excerpt (pin names and nets, part order shuffled) for the footprints in the layout excerpt that follows; sources: Cadence DE-HDL packaged netlist, KiCad conversion of 12092022_DA0F0TMDCD0_F0T_Management_Board_D_brd_V3_OCP.brd

R14  Q_RES  4.7K 1% EMPTY  pkg 0402LF  page 26 : A = P3V3_AUX ; B = FRU_E2
R688  Q_RES  33.2 1% CHIP  pkg 0402LF  page 13 : A = RST_SGPIO_RESET_BMC_N ; B = RST_SGPIO_RESET_N

(kicad_pcb
	(version 20260206)
	(generator "pcbnew")
	(generator_version "10.0")
	(general
		(thickness 1.6)
		(legacy_teardrops no)
	)
	(paper "A4")
	(title_block
		(title "12092022_DA0F0TMDCD0_F0T_Management_Board_D_brd_V3_OCP.brd")
		(comment 1 "Grand Teton / footprints 1366-1367 of 1440")
	)
	(layers
		(0 "F.Cu" signal "TOP")
		(4 "In1.Cu" signal "GND")
		(6 "In2.Cu" signal "IN1")
		(8 "In3.Cu" signal "GND1")
		(10 "In4.Cu" signal "IN2")
		(12 "In5.Cu" signal "VCC")
		(14 "In6.Cu" signal "VCC1")
		(16 "In7.Cu" signal "IN3")
		(18 "In8.Cu" signal "GND2")
		(20 "In9.Cu" signal "IN4")
		(22 "In10.Cu" signal "GND3")
		(2 "B.Cu" signal "BOTTOM")
		(9 "F.Adhes" user "F.Adhesive")
		(11 "B.Adhes" user "B.Adhesive")
		(13 "F.Paste" user "Package Geometry/Pastemask Top")
		(15 "B.Paste" user "Package Geometry/Pastemask Bottom")
		(5 "F.SilkS" user "Ref Des/Silkscreen Top")
		(7 "B.SilkS" user "Ref Des/Silkscreen Bottom")
		(1 "F.Mask" user "Board Geometry/Soldermask Top")
		(3 "B.Mask" user "Board Geometry/Soldermask Bottom")
		(17 "Dwgs.User" user "User.Drawings")
		(19 "Cmts.User" user "User.Comments")
		(21 "Eco1.User" user "User.Eco1")
		(23 "Eco2.User" user "User.Eco2")
		(25 "Edge.Cuts" user "Board Geometry/Outline")
		(27 "Margin" user)
		(31 "F.CrtYd" user "Package Geometry/Place Bound Top")
		(29 "B.CrtYd" user "Package Geometry/Place Bound Bottom")
		(35 "F.Fab" user "Ref Des/Assembly Top")
		(33 "B.Fab" user "Ref Des/Assembly Bottom")
	)
	(footprint ""
		(layer "B.Cu")
		(at 41.314878 -30.816804 90)
		(property "Reference" "R688"
			(at 0 0 90)
			(layer "B.SilkS")
			(hide yes)
			(effects
				(font
					(size 1.27 1.27)
				)
				(justify mirror)
			)
		)
		(property "Value" ""
			(at 0 0 90)
			(layer "B.Fab")
			(effects
				(font
					(size 1.27 1.27)
				)
				(justify mirror)
			)
		)
		(duplicate_pad_numbers_are_jumpers no)
		(fp_line
			(start 0.7874 -0.4064)
			(end -0.7874 -0.4064)
			(stroke
				(width 0.1524)
				(type default)
			)
			(layer "B.SilkS")
		)
		(fp_line
			(start -0.7874 -0.4064)
			(end -0.7874 0.4064)
			(stroke
				(width 0.1524)
				(type default)
			)
			(layer "B.SilkS")
		)
		(fp_line
			(start 0.7874 0.4064)
			(end 0.7874 -0.4064)
			(stroke
				(width 0.1524)
				(type default)
			)
			(layer "B.SilkS")
		)
		(fp_line
			(start -0.7874 0.4064)
			(end 0.7874 0.4064)
			(stroke
				(width 0.1524)
				(type default)
			)
			(layer "B.SilkS")
		)
		(fp_line
			(start 0.67945 -0.305054)
			(end 0.12065 -0.305054)
			(stroke
				(width 0.1)
				(type default)
			)
			(layer "B.Fab")
		)
		(fp_line
			(start 0.12065 -0.305054)
			(end 0.12065 -0.2794)
			(stroke
				(width 0.1)
				(type default)
			)
			(layer "B.Fab")
		)
		(fp_line
			(start -0.12065 -0.3048)
			(end -0.67945 -0.3048)
			(stroke
				(width 0.1)
				(type default)
			)
			(layer "B.Fab")
		)
		(fp_line
			(start -0.67945 -0.3048)
			(end -0.67945 0.3048)
			(stroke
				(width 0.1)
				(type default)
			)
			(layer "B.Fab")
		)
		(fp_line
			(start 0.12065 -0.2794)
			(end -0.12065 -0.2794)
			(stroke
				(width 0.1)
				(type default)
			)
			(layer "B.Fab")
		)
		(fp_line
			(start -0.12065 -0.2794)
			(end -0.12065 -0.3048)
			(stroke
				(width 0.1)
				(type default)
			)
			(layer "B.Fab")
		)
		(fp_line
			(start 0.12065 0.2794)
			(end 0.12065 0.3048)
			(stroke
				(width 0.1)
				(type default)
			)
			(layer "B.Fab")
		)
		(fp_line
			(start -0.120396 0.2794)
			(end 0.12065 0.2794)
			(stroke
				(width 0.1)
				(type default)
			)
			(layer "B.Fab")
		)
		(fp_line
			(start 0.67945 0.3048)
			(end 0.67945 -0.305054)
			(stroke
				(width 0.1)
				(type default)
			)
			(layer "B.Fab")
		)
		(fp_line
			(start 0.12065 0.3048)
			(end 0.67945 0.3048)
			(stroke
				(width 0.1)
				(type default)
			)
			(layer "B.Fab")
		)
		(fp_line
			(start -0.120396 0.3048)
			(end -0.120396 0.2794)
			(stroke
				(width 0.1)
				(type default)
			)
			(layer "B.Fab")
		)
		(fp_line
			(start -0.67945 0.3048)
			(end -0.120396 0.3048)
			(stroke
				(width 0.1)
				(type default)
			)
			(layer "B.Fab")
		)
		(pad "1" smd circle
			(at 0.40005 0 270)
			(size 0 0)
			(layers "B.Cu" "B.Mask" "B.Paste")
			(net "RST_SGPIO_RESET_BMC_N")
		)
		(pad "2" smd circle
			(at -0.40005 0 270)
			(size 0 0)
			(layers "B.Cu" "B.Mask" "B.Paste")
			(net "RST_SGPIO_RESET_N")
		)
	)
	(footprint ""
		(layer "B.Cu")
		(at 85.32241 -26.587704)
		(property "Reference" "R14"
			(at 0 0 0)
			(layer "B.SilkS")
			(hide yes)
			(effects
				(font
					(size 1.27 1.27)
				)
				(justify mirror)
			)
		)
		(property "Value" ""
			(at 0 0 0)
			(layer "B.Fab")
			(effects
				(font
					(size 1.27 1.27)
				)
				(justify mirror)
			)
		)
		(duplicate_pad_numbers_are_jumpers no)
		(fp_line
			(start -0.7874 -0.4064)
			(end -0.7874 0.4064)
			(stroke
				(width 0.1524)
				(type default)
			)
			(layer "B.SilkS")
		)
		(fp_line
			(start -0.7874 0.4064)
			(end 0.7874 0.4064)
			(stroke
				(width 0.1524)
				(type default)
			)
			(layer "B.SilkS")
		)
		(fp_line
			(start 0.7874 -0.4064)
			(end -0.7874 -0.4064)
			(stroke
				(width 0.1524)
				(type default)
			)
			(layer "B.SilkS")
		)
		(fp_line
			(start 0.7874 0.4064)
			(end 0.7874 -0.4064)
			(stroke
				(width 0.1524)
				(type default)
			)
			(layer "B.SilkS")
		)
		(fp_line
			(start -0.67945 -0.3048)
			(end -0.67945 0.3048)
			(stroke
				(width 0.1)
				(type default)
			)
			(layer "B.Fab")
		)
		(fp_line
			(start -0.67945 0.3048)
			(end -0.120396 0.3048)
			(stroke
				(width 0.1)
				(type default)
			)
			(layer "B.Fab")
		)
		(fp_line
			(start -0.12065 -0.3048)
			(end -0.67945 -0.3048)
			(stroke
				(width 0.1)
				(type default)
			)
			(layer "B.Fab")
		)
		(fp_line
			(start -0.12065 -0.2794)
			(end -0.12065 -0.3048)
			(stroke
				(width 0.1)
				(type default)
			)
			(layer "B.Fab")
		)
		(fp_line
			(start -0.120396 0.2794)
			(end 0.12065 0.2794)
			(stroke
				(width 0.1)
				(type default)
			)
			(layer "B.Fab")
		)
		(fp_line
			(start -0.120396 0.3048)
			(end -0.120396 0.2794)
			(stroke
				(width 0.1)
				(type default)
			)
			(layer "B.Fab")
		)
		(fp_line
			(start 0.12065 -0.305054)
			(end 0.12065 -0.2794)
			(stroke
				(width 0.1)
				(type default)
			)
			(layer "B.Fab")
		)
		(fp_line
			(start 0.12065 -0.2794)
			(end -0.12065 -0.2794)
			(stroke
				(width 0.1)
				(type default)
			)
			(layer "B.Fab")
		)
		(fp_line
			(start 0.12065 0.2794)
			(end 0.12065 0.3048)
			(stroke
				(width 0.1)
				(type default)
			)
			(layer "B.Fab")
		)
		(fp_line
			(start 0.12065 0.3048)
			(end 0.67945 0.3048)
			(stroke
				(width 0.1)
				(type default)
			)
			(layer "B.Fab")
		)
		(fp_line
			(start 0.67945 -0.305054)
			(end 0.12065 -0.305054)
			(stroke
				(width 0.1)
				(type default)
			)
			(layer "B.Fab")
		)
		(fp_line
			(start 0.67945 0.3048)
			(end 0.67945 -0.305054)
			(stroke
				(width 0.1)
				(type default)
			)
			(layer "B.Fab")
		)
		(pad "1" smd circle
			(at 0.40005 0 180)
			(size 0 0)
			(layers "B.Cu" "B.Mask" "B.Paste")
			(net "P3V3_AUX")
		)
		(pad "2" smd circle
			(at -0.40005 0 180)
			(size 0 0)
			(layers "B.Cu" "B.Mask" "B.Paste")
			(net "FRU_E2")
		)
	)
)
